#ISCELL
  logical_power cad_note *
  *
#ISCELL
  mstr_misc dns *
  *
#ISCELL
  pure_quanta quanta_title_block_c *
  *
#ISCELL
  logical_power universal_gnd *
  page55_i10
#ISCELL
  logical_power universal_gnd *
  page55_i14
#CELL
  pure_quanta nb695gdz *
  page55_i15
#CELL
  pure_quanta q_cap *
  page55_i16
#ISCELL
  logical_power universal_gnd *
  page55_i17
#CELL
  pure_quanta q_res *
  page55_i18
#CELL
  pure_quanta q_cap *
  page55_i19
#ISCELL
  logical_power vccaux15 *
  page55_i2
#CELL
  pure_quanta q_inductor *
  page55_i21
#CELL
  pure_quanta q_cap *
  page55_i23
#CELL
  pure_quanta q_cap *
  page55_i24
#CELL
  pure_quanta q_cap *
  page55_i25
#ISCELL
  logical_power universal_gnd *
  page55_i27
#CELL
  pure_quanta q_cap *
  page55_i28
#CELL
  pure_quanta q_cap *
  page55_i29
#ISCELL
  logical_power vccaux15 *
  page55_i30
#CELL
  pure_quanta q_inductor *
  page55_i31
#ISCELL
  logical_power vccaux15 *
  page55_i34
#ISCELL
  standard offpage *
  page55_i35
#CELL
  pure_quanta q_res *
  page55_i38
#ISCELL
  standard offpage *
  page55_i39
#ISCELL
  logical_power universal_gnd *
  page55_i4
#ISCELL
  standard offpage *
  page55_i40
#CELL
  pure_quanta q_res *
  page55_i41
#CELL
  pure_quanta q_cap *
  page55_i42
#CELL
  pure_quanta q_cap *
  page55_i43
#ISCELL
  logical_power vccaux15 *
  page55_i44
#CELL
  pure_quanta q_res *
  page55_i45
#ISCELL
  logical_power vccaux15 *
  page55_i46
#ISCELL
  logical_power vccaux15 *
  page55_i47
#CELL
  pure_quanta q_res *
  page55_i48
#ISCELL
  logical_power vccaux15 *
  page55_i49
#ISCELL
  logical_power universal_gnd *
  page55_i5
#CELL
  pure_quanta q_res *
  page55_i50
#ISCELL
  logical_power universal_gnd *
  page55_i51
#CELL
  pure_quanta q_cap *
  page55_i52
#ISCELL
  logical_power universal_gnd *
  page55_i53
#CELL
  pure_quanta q_cap *
  page55_i54
#ISCELL
  standard offpage *
  page55_i55
#ISCELL
  standard offpage *
  page55_i56
#ISCELL
  logical_power universal_gnd *
  page55_i57
#CELL
  pure_quanta q_res *
  page55_i6
#ISCELL
  logical_power universal_gnd *
  page55_i60
#CELL
  pure_quanta q_cap *
  page55_i61
#CELL
  pure_quanta 74lvc1g08gw *
  page55_i63
#ISCELL
  standard offpage *
  page55_i67
#CELL
  pure_quanta q_res *
  page55_i68
#ISCELL
  standard offpage *
  page55_i69
#CELL
  pure_quanta q_cap *
  page55_i7
#CELL
  pure_quanta q_res *
  page55_i70
#ISCELL
  standard offpage *
  page55_i71
#ISCELL
  logical_power universal_power *
  page55_i72
#CELL
  pure_quanta q_res *
  page55_i8
#ISCELL
  logical_power vccaux15 *
  page55_i9
